(kicad_pcb
	(version 20260206)
	(generator "pcbnew")
	(generator_version "10.0")
	(general
		(thickness 1.6)
		(legacy_teardrops no)
	)
	(paper "A4")
	(title_block
		(title "01162023_DA0F0TEBIF0_F0T_Expander_BD_F_brd_V02_OCP.brd")
		(comment 1 "Grand Teton / footprints 1709-1715 of 9728")
	)
	(layers
		(0 "F.Cu" signal "TOP")
		(4 "In1.Cu" signal "GND")
		(6 "In2.Cu" signal "VCC")
		(8 "In3.Cu" signal "VCC1")
		(10 "In4.Cu" signal "GND1")
		(12 "In5.Cu" signal "IN1")
		(14 "In6.Cu" signal "GND2")
		(16 "In7.Cu" signal "IN2")
		(18 "In8.Cu" signal "GND3")
		(20 "In9.Cu" signal "IN3")
		(22 "In10.Cu" signal "GND4")
		(24 "In11.Cu" signal "IN4")
		(26 "In12.Cu" signal "GND5")
		(28 "In13.Cu" signal "IN5")
		(30 "In14.Cu" signal "GND6")
		(32 "In15.Cu" signal "IN6")
		(34 "In16.Cu" signal "GND7")
		(2 "B.Cu" signal "BOTTOM")
		(9 "F.Adhes" user "F.Adhesive")
		(11 "B.Adhes" user "B.Adhesive")
		(13 "F.Paste" user "Package Geometry/Pastemask Top")
		(15 "B.Paste" user "Package Geometry/Pastemask Bottom")
		(5 "F.SilkS" user "Ref Des/Silkscreen Top")
		(7 "B.SilkS" user "Ref Des/Silkscreen Bottom")
		(1 "F.Mask" user "Board Geometry/Soldermask Top")
		(3 "B.Mask" user "Board Geometry/Soldermask Bottom")
		(17 "Dwgs.User" user "User.Drawings")
		(19 "Cmts.User" user "User.Comments")
		(21 "Eco1.User" user "User.Eco1")
		(23 "Eco2.User" user "User.Eco2")
		(25 "Edge.Cuts" user "Board Geometry/Outline")
		(27 "Margin" user)
		(31 "F.CrtYd" user "Package Geometry/Place Bound Top")
		(29 "B.CrtYd" user "Package Geometry/Place Bound Bottom")
		(35 "F.Fab" user "Ref Des/Assembly Top")
		(33 "B.Fab" user "Ref Des/Assembly Bottom")
	)
	(footprint ""
		(layer "F.Cu")
		(at 104.003094 -397.512286 90)
		(property "Reference" "C3637"
			(at 0 0 90)
			(layer "F.SilkS")
			(hide yes)
			(effects
				(font
					(size 1.27 1.27)
				)
			)
		)
		(property "Value" ""
			(at 0 0 90)
			(layer "F.Fab")
			(effects
				(font
					(size 1.27 1.27)
				)
			)
		)
		(duplicate_pad_numbers_are_jumpers no)
		(fp_line
			(start 0.7874 -0.4064)
			(end 0.7874 0.4064)
			(stroke
				(width 0.1524)
				(type default)
			)
			(layer "F.SilkS")
		)
		(fp_line
			(start -0.7874 -0.4064)
			(end 0.7874 -0.4064)
			(stroke
				(width 0.1524)
				(type default)
			)
			(layer "F.SilkS")
		)
		(fp_line
			(start 0.7874 0.4064)
			(end -0.7874 0.4064)
			(stroke
				(width 0.1524)
				(type default)
			)
			(layer "F.SilkS")
		)
		(fp_line
			(start -0.7874 0.4064)
			(end -0.7874 -0.4064)
			(stroke
				(width 0.1524)
				(type default)
			)
			(layer "F.SilkS")
		)
		(fp_line
			(start -0.12065 -0.305054)
			(end -0.12065 -0.2794)
			(stroke
				(width 0.1)
				(type default)
			)
			(layer "F.Fab")
		)
		(fp_line
			(start -0.67945 -0.305054)
			(end -0.12065 -0.305054)
			(stroke
				(width 0.1)
				(type default)
			)
			(layer "F.Fab")
		)
		(fp_line
			(start 0.67945 -0.3048)
			(end 0.67945 0.3048)
			(stroke
				(width 0.1)
				(type default)
			)
			(layer "F.Fab")
		)
		(fp_line
			(start 0.12065 -0.3048)
			(end 0.67945 -0.3048)
			(stroke
				(width 0.1)
				(type default)
			)
			(layer "F.Fab")
		)
		(fp_line
			(start 0.12065 -0.2794)
			(end 0.12065 -0.3048)
			(stroke
				(width 0.1)
				(type default)
			)
			(layer "F.Fab")
		)
		(fp_line
			(start -0.12065 -0.2794)
			(end 0.12065 -0.2794)
			(stroke
				(width 0.1)
				(type default)
			)
			(layer "F.Fab")
		)
		(fp_line
			(start 0.120396 0.2794)
			(end -0.12065 0.2794)
			(stroke
				(width 0.1)
				(type default)
			)
			(layer "F.Fab")
		)
		(fp_line
			(start -0.12065 0.2794)
			(end -0.12065 0.3048)
			(stroke
				(width 0.1)
				(type default)
			)
			(layer "F.Fab")
		)
		(fp_line
			(start 0.67945 0.3048)
			(end 0.120396 0.3048)
			(stroke
				(width 0.1)
				(type default)
			)
			(layer "F.Fab")
		)
		(fp_line
			(start 0.120396 0.3048)
			(end 0.120396 0.2794)
			(stroke
				(width 0.1)
				(type default)
			)
			(layer "F.Fab")
		)
		(fp_line
			(start -0.12065 0.3048)
			(end -0.67945 0.3048)
			(stroke
				(width 0.1)
				(type default)
			)
			(layer "F.Fab")
		)
		(fp_line
			(start -0.67945 0.3048)
			(end -0.67945 -0.305054)
			(stroke
				(width 0.1)
				(type default)
			)
			(layer "F.Fab")
		)
		(pad "1" smd circle
			(at -0.40005 0 90)
			(size 0 0)
			(layers "F.Cu" "F.Mask" "F.Paste")
			(net "RST_BIC_USB_HUB_R1_N")
		)
		(pad "2" smd circle
			(at 0.40005 0 90)
			(size 0 0)
			(layers "F.Cu" "F.Mask" "F.Paste")
			(net "GND")
		)
	)
	(footprint ""
		(layer "F.Cu")
		(at 52.459382 -22.955504 90)
		(property "Reference" "R1644"
			(at 0 0 90)
			(layer "F.SilkS")
			(hide yes)
			(effects
				(font
					(size 1.27 1.27)
				)
			)
		)
		(property "Value" ""
			(at 0 0 90)
			(layer "F.Fab")
			(effects
				(font
					(size 1.27 1.27)
				)
			)
		)
		(duplicate_pad_numbers_are_jumpers no)
		(fp_line
			(start 0.7874 -0.4064)
			(end 0.7874 0.4064)
			(stroke
				(width 0.1524)
				(type default)
			)
			(layer "F.SilkS")
		)
		(fp_line
			(start -0.7874 -0.4064)
			(end 0.7874 -0.4064)
			(stroke
				(width 0.1524)
				(type default)
			)
			(layer "F.SilkS")
		)
		(fp_line
			(start 0.7874 0.4064)
			(end -0.7874 0.4064)
			(stroke
				(width 0.1524)
				(type default)
			)
			(layer "F.SilkS")
		)
		(fp_line
			(start -0.7874 0.4064)
			(end -0.7874 -0.4064)
			(stroke
				(width 0.1524)
				(type default)
			)
			(layer "F.SilkS")
		)
		(fp_line
			(start -0.12065 -0.305054)
			(end -0.12065 -0.2794)
			(stroke
				(width 0.1)
				(type default)
			)
			(layer "F.Fab")
		)
		(fp_line
			(start -0.67945 -0.305054)
			(end -0.12065 -0.305054)
			(stroke
				(width 0.1)
				(type default)
			)
			(layer "F.Fab")
		)
		(fp_line
			(start 0.67945 -0.3048)
			(end 0.67945 0.3048)
			(stroke
				(width 0.1)
				(type default)
			)
			(layer "F.Fab")
		)
		(fp_line
			(start 0.12065 -0.3048)
			(end 0.67945 -0.3048)
			(stroke
				(width 0.1)
				(type default)
			)
			(layer "F.Fab")
		)
		(fp_line
			(start 0.12065 -0.2794)
			(end 0.12065 -0.3048)
			(stroke
				(width 0.1)
				(type default)
			)
			(layer "F.Fab")
		)
		(fp_line
			(start -0.12065 -0.2794)
			(end 0.12065 -0.2794)
			(stroke
				(width 0.1)
				(type default)
			)
			(layer "F.Fab")
		)
		(fp_line
			(start 0.120396 0.2794)
			(end -0.12065 0.2794)
			(stroke
				(width 0.1)
				(type default)
			)
			(layer "F.Fab")
		)
		(fp_line
			(start -0.12065 0.2794)
			(end -0.12065 0.3048)
			(stroke
				(width 0.1)
				(type default)
			)
			(layer "F.Fab")
		)
		(fp_line
			(start 0.67945 0.3048)
			(end 0.120396 0.3048)
			(stroke
				(width 0.1)
				(type default)
			)
			(layer "F.Fab")
		)
		(fp_line
			(start 0.120396 0.3048)
			(end 0.120396 0.2794)
			(stroke
				(width 0.1)
				(type default)
			)
			(layer "F.Fab")
		)
		(fp_line
			(start -0.12065 0.3048)
			(end -0.67945 0.3048)
			(stroke
				(width 0.1)
				(type default)
			)
			(layer "F.Fab")
		)
		(fp_line
			(start -0.67945 0.3048)
			(end -0.67945 -0.305054)
			(stroke
				(width 0.1)
				(type default)
			)
			(layer "F.Fab")
		)
		(pad "1" smd circle
			(at -0.40005 0 90)
			(size 0 0)
			(layers "F.Cu" "F.Mask" "F.Paste")
			(net "SMB_BIC_I2C9_MUX0_SSD1_R_SCL")
		)
		(pad "2" smd circle
			(at 0.40005 0 90)
			(size 0 0)
			(layers "F.Cu" "F.Mask" "F.Paste")
			(net "SMB_ISO_SSD1_SCL")
		)
	)
	(footprint ""
		(layer "F.Cu")
		(at 115.356386 -88.469978 180)
		(property "Reference" "R1148"
			(at 0 0 180)
			(layer "F.SilkS")
			(hide yes)
			(effects
				(font
					(size 1.27 1.27)
				)
			)
		)
		(property "Value" ""
			(at 0 0 180)
			(layer "F.Fab")
			(effects
				(font
					(size 1.27 1.27)
				)
			)
		)
		(duplicate_pad_numbers_are_jumpers no)
		(fp_line
			(start -0.7874 -0.4064)
			(end 0.7874 -0.4064)
			(stroke
				(width 0.1524)
				(type default)
			)
			(layer "F.SilkS")
		)
		(fp_line
			(start 0.67945 0.3048)
			(end 0.120396 0.3048)
			(stroke
				(width 0.1)
				(type default)
			)
			(layer "F.Fab")
		)
		(fp_line
			(start 0.67945 -0.3048)
			(end 0.67945 0.3048)
			(stroke
				(width 0.1)
				(type default)
			)
			(layer "F.Fab")
		)
		(fp_line
			(start 0.12065 -0.2794)
			(end 0.12065 -0.3048)
			(stroke
				(width 0.1)
				(type default)
			)
			(layer "F.Fab")
		)
		(fp_line
			(start 0.12065 -0.3048)
			(end 0.67945 -0.3048)
			(stroke
				(width 0.1)
				(type default)
			)
			(layer "F.Fab")
		)
		(fp_line
			(start 0.120396 0.3048)
			(end 0.120396 0.2794)
			(stroke
				(width 0.1)
				(type default)
			)
			(layer "F.Fab")
		)
		(fp_line
			(start 0.120396 0.2794)
			(end -0.12065 0.2794)
			(stroke
				(width 0.1)
				(type default)
			)
			(layer "F.Fab")
		)
		(fp_line
			(start -0.12065 0.3048)
			(end -0.67945 0.3048)
			(stroke
				(width 0.1)
				(type default)
			)
			(layer "F.Fab")
		)
		(fp_line
			(start -0.12065 0.2794)
			(end -0.12065 0.3048)
			(stroke
				(width 0.1)
				(type default)
			)
			(layer "F.Fab")
		)
		(fp_line
			(start -0.12065 -0.2794)
			(end 0.12065 -0.2794)
			(stroke
				(width 0.1)
				(type default)
			)
			(layer "F.Fab")
		)
		(fp_line
			(start -0.12065 -0.305054)
			(end -0.12065 -0.2794)
			(stroke
				(width 0.1)
				(type default)
			)
			(layer "F.Fab")
		)
		(fp_line
			(start -0.67945 0.3048)
			(end -0.67945 -0.305054)
			(stroke
				(width 0.1)
				(type default)
			)
			(layer "F.Fab")
		)
		(fp_line
			(start -0.67945 -0.305054)
			(end -0.12065 -0.305054)
			(stroke
				(width 0.1)
				(type default)
			)
			(layer "F.Fab")
		)
		(pad "1" smd circle
			(at -0.40005 0 180)
			(size 0 0)
			(layers "F.Cu" "F.Mask" "F.Paste")
			(net "CLK_100M_DB800ZL_SSD6_R_DP")
		)
		(pad "2" smd circle
			(at 0.40005 0 180)
			(size 0 0)
			(layers "F.Cu" "F.Mask" "F.Paste")
			(net "CLK_100M_DB800ZL_SSD6_DP")
		)
	)
	(footprint ""
		(layer "F.Cu")
		(at 312.477404 -350.098614 90)
		(property "Reference" "C549"
			(at 0 0 90)
			(layer "F.SilkS")
			(hide yes)
			(effects
				(font
					(size 1.27 1.27)
				)
			)
		)
		(property "Value" ""
			(at 0 0 90)
			(layer "F.Fab")
			(effects
				(font
					(size 1.27 1.27)
				)
			)
		)
		(duplicate_pad_numbers_are_jumpers no)
		(fp_line
			(start 0.299974 -0.150114)
			(end 0.299974 0.150114)
			(stroke
				(width 0.1)
				(type default)
			)
			(layer "F.Fab")
		)
		(fp_line
			(start -0.299974 -0.150114)
			(end 0.299974 -0.150114)
			(stroke
				(width 0.1)
				(type default)
			)
			(layer "F.Fab")
		)
		(fp_line
			(start 0.299974 0.150114)
			(end -0.299974 0.150114)
			(stroke
				(width 0.1)
				(type default)
			)
			(layer "F.Fab")
		)
		(fp_line
			(start -0.299974 0.150114)
			(end -0.299974 -0.150114)
			(stroke
				(width 0.1)
				(type default)
			)
			(layer "F.Fab")
		)
		(pad "1" smd rect
			(at -0.2667 0 90)
			(size 0.3048 0.381)
			(layers "F.Cu" "F.Mask" "F.Paste")
			(net "P5E_PEX2_STN5_TX_DP<80>")
		)
		(pad "2" smd rect
			(at 0.2667 0 90)
			(size 0.3048 0.381)
			(layers "F.Cu" "F.Mask" "F.Paste")
			(net "P5E_PEX2_STN5_TX_C_DP<80>")
		)
	)
	(footprint ""
		(layer "F.Cu")
		(at 324.587108 -300.650402 -90)
		(property "Reference" "R3977"
			(at 0 0 270)
			(layer "F.SilkS")
			(hide yes)
			(effects
				(font
					(size 1.27 1.27)
				)
			)
		)
		(property "Value" ""
			(at 0 0 270)
			(layer "F.Fab")
			(effects
				(font
					(size 1.27 1.27)
				)
			)
		)
		(duplicate_pad_numbers_are_jumpers no)
		(fp_line
			(start -0.7874 0.4064)
			(end -0.7874 -0.4064)
			(stroke
				(width 0.1524)
				(type default)
			)
			(layer "F.SilkS")
		)
		(fp_line
			(start 0.7874 0.4064)
			(end -0.7874 0.4064)
			(stroke
				(width 0.1524)
				(type default)
			)
			(layer "F.SilkS")
		)
		(fp_line
			(start -0.7874 -0.4064)
			(end 0.7874 -0.4064)
			(stroke
				(width 0.1524)
				(type default)
			)
			(layer "F.SilkS")
		)
		(fp_line
			(start 0.7874 -0.4064)
			(end 0.7874 0.4064)
			(stroke
				(width 0.1524)
				(type default)
			)
			(layer "F.SilkS")
		)
		(fp_line
			(start -0.67945 0.3048)
			(end -0.67945 -0.305054)
			(stroke
				(width 0.1)
				(type default)
			)
			(layer "F.Fab")
		)
		(fp_line
			(start -0.12065 0.3048)
			(end -0.67945 0.3048)
			(stroke
				(width 0.1)
				(type default)
			)
			(layer "F.Fab")
		)
		(fp_line
			(start 0.120396 0.3048)
			(end 0.120396 0.2794)
			(stroke
				(width 0.1)
				(type default)
			)
			(layer "F.Fab")
		)
		(fp_line
			(start 0.67945 0.3048)
			(end 0.120396 0.3048)
			(stroke
				(width 0.1)
				(type default)
			)
			(layer "F.Fab")
		)
		(fp_line
			(start -0.12065 0.2794)
			(end -0.12065 0.3048)
			(stroke
				(width 0.1)
				(type default)
			)
			(layer "F.Fab")
		)
		(fp_line
			(start 0.120396 0.2794)
			(end -0.12065 0.2794)
			(stroke
				(width 0.1)
				(type default)
			)
			(layer "F.Fab")
		)
		(fp_line
			(start -0.12065 -0.2794)
			(end 0.12065 -0.2794)
			(stroke
				(width 0.1)
				(type default)
			)
			(layer "F.Fab")
		)
		(fp_line
			(start 0.12065 -0.2794)
			(end 0.12065 -0.3048)
			(stroke
				(width 0.1)
				(type default)
			)
			(layer "F.Fab")
		)
		(fp_line
			(start 0.12065 -0.3048)
			(end 0.67945 -0.3048)
			(stroke
				(width 0.1)
				(type default)
			)
			(layer "F.Fab")
		)
		(fp_line
			(start 0.67945 -0.3048)
			(end 0.67945 0.3048)
			(stroke
				(width 0.1)
				(type default)
			)
			(layer "F.Fab")
		)
		(fp_line
			(start -0.67945 -0.305054)
			(end -0.12065 -0.305054)
			(stroke
				(width 0.1)
				(type default)
			)
			(layer "F.Fab")
		)
		(fp_line
			(start -0.12065 -0.305054)
			(end -0.12065 -0.2794)
			(stroke
				(width 0.1)
				(type default)
			)
			(layer "F.Fab")
		)
		(pad "1" smd circle
			(at -0.40005 0 270)
			(size 0 0)
			(layers "F.Cu" "F.Mask" "F.Paste")
			(net "I2C0_PEX2_SHPC_SCL")
		)
		(pad "2" smd circle
			(at 0.40005 0 270)
			(size 0 0)
			(layers "F.Cu" "F.Mask" "F.Paste")
			(net "I2C_PEX2_HOST_SCL")
		)
	)
	(footprint ""
		(layer "F.Cu")
		(at 217.235786 -219.318586 180)
		(property "Reference" "R1498"
			(at 0 0 180)
			(layer "F.SilkS")
			(hide yes)
			(effects
				(font
					(size 1.27 1.27)
				)
			)
		)
		(property "Value" ""
			(at 0 0 180)
			(layer "F.Fab")
			(effects
				(font
					(size 1.27 1.27)
				)
			)
		)
		(duplicate_pad_numbers_are_jumpers no)
		(fp_line
			(start 0.7874 0.4064)
			(end -0.7874 0.4064)
			(stroke
				(width 0.1524)
				(type default)
			)
			(layer "F.SilkS")
		)
		(fp_line
			(start 0.7874 -0.4064)
			(end 0.7874 0.4064)
			(stroke
				(width 0.1524)
				(type default)
			)
			(layer "F.SilkS")
		)
		(fp_line
			(start -0.7874 0.4064)
			(end -0.7874 -0.4064)
			(stroke
				(width 0.1524)
				(type default)
			)
			(layer "F.SilkS")
		)
		(fp_line
			(start -0.7874 -0.4064)
			(end 0.7874 -0.4064)
			(stroke
				(width 0.1524)
				(type default)
			)
			(layer "F.SilkS")
		)
		(fp_line
			(start 0.67945 0.3048)
			(end 0.120396 0.3048)
			(stroke
				(width 0.1)
				(type default)
			)
			(layer "F.Fab")
		)
		(fp_line
			(start 0.67945 -0.3048)
			(end 0.67945 0.3048)
			(stroke
				(width 0.1)
				(type default)
			)
			(layer "F.Fab")
		)
		(fp_line
			(start 0.12065 -0.2794)
			(end 0.12065 -0.3048)
			(stroke
				(width 0.1)
				(type default)
			)
			(layer "F.Fab")
		)
		(fp_line
			(start 0.12065 -0.3048)
			(end 0.67945 -0.3048)
			(stroke
				(width 0.1)
				(type default)
			)
			(layer "F.Fab")
		)
		(fp_line
			(start 0.120396 0.3048)
			(end 0.120396 0.2794)
			(stroke
				(width 0.1)
				(type default)
			)
			(layer "F.Fab")
		)
		(fp_line
			(start 0.120396 0.2794)
			(end -0.12065 0.2794)
			(stroke
				(width 0.1)
				(type default)
			)
			(layer "F.Fab")
		)
		(fp_line
			(start -0.12065 0.3048)
			(end -0.67945 0.3048)
			(stroke
				(width 0.1)
				(type default)
			)
			(layer "F.Fab")
		)
		(fp_line
			(start -0.12065 0.2794)
			(end -0.12065 0.3048)
			(stroke
				(width 0.1)
				(type default)
			)
			(layer "F.Fab")
		)
		(fp_line
			(start -0.12065 -0.2794)
			(end 0.12065 -0.2794)
			(stroke
				(width 0.1)
				(type default)
			)
			(layer "F.Fab")
		)
		(fp_line
			(start -0.12065 -0.305054)
			(end -0.12065 -0.2794)
			(stroke
				(width 0.1)
				(type default)
			)
			(layer "F.Fab")
		)
		(fp_line
			(start -0.67945 0.3048)
			(end -0.67945 -0.305054)
			(stroke
				(width 0.1)
				(type default)
			)
			(layer "F.Fab")
		)
		(fp_line
			(start -0.67945 -0.305054)
			(end -0.12065 -0.305054)
			(stroke
				(width 0.1)
				(type default)
			)
			(layer "F.Fab")
		)
		(pad "1" smd circle
			(at -0.40005 0 180)
			(size 0 0)
			(layers "F.Cu" "F.Mask" "F.Paste")
			(net "SMB_NIC4_SCL")
		)
		(pad "2" smd circle
			(at 0.40005 0 180)
			(size 0 0)
			(layers "F.Cu" "F.Mask" "F.Paste")
			(net "SMB_NIC4_R_SCL")
		)
	)
	(footprint ""
		(layer "F.Cu")
		(at 133.88848 -249.644916)
		(property "Reference" "PJP1"
			(at -1.4224 -4.562348 0)
			(unlocked yes)
			(layer "F.SilkS")
			(effects
				(font
					(size 0.7874 0.5842)
					(thickness 0.1524)
				)
				(justify left)
			)
		)
		(property "Value" ""
			(at 0 0 0)
			(layer "F.Fab")
			(effects
				(font
					(size 1.27 1.27)
				)
			)
		)
		(duplicate_pad_numbers_are_jumpers no)
		(fp_line
			(start -1.27 -3.81)
			(end 1.27 -3.81)
			(stroke
				(width 0.1524)
				(type default)
			)
			(layer "F.SilkS")
		)
		(fp_line
			(start -1.27 -0.7747)
			(end -1.27 -3.81)
			(stroke
				(width 0.1524)
				(type default)
			)
			(layer "F.SilkS")
		)
		(fp_line
			(start -1.27 3.81)
			(end -1.27 0.7747)
			(stroke
				(width 0.1524)
				(type default)
			)
			(layer "F.SilkS")
		)
		(fp_line
			(start 1.27 -3.81)
			(end 1.27 -3.3147)
			(stroke
				(width 0.1524)
				(type default)
			)
			(layer "F.SilkS")
		)
		(fp_line
			(start 1.27 -1.7653)
			(end 1.27 1.7653)
			(stroke
				(width 0.1524)
				(type default)
			)
			(layer "F.SilkS")
		)
		(fp_line
			(start 1.27 3.3147)
			(end 1.27 3.81)
			(stroke
				(width 0.1524)
				(type default)
			)
			(layer "F.SilkS")
		)
		(fp_line
			(start 1.27 3.81)
			(end -1.27 3.81)
			(stroke
				(width 0.1524)
				(type default)
			)
			(layer "F.SilkS")
		)
		(fp_poly
			(pts
				(xy 4.3942 -3.048) (xy 4.3942 -2.032) (xy 3.3782 -2.54)
			)
			(stroke
				(width 0)
				(type default)
			)
			(fill yes)
			(layer "F.SilkS")
		)
		(fp_line
			(start -1.27 -3.81)
			(end -1.27 3.81)
			(stroke
				(width 0.1)
				(type default)
			)
			(layer "F.Fab")
		)
		(fp_line
			(start -1.27 3.81)
			(end 1.27 3.81)
			(stroke
				(width 0.1)
				(type default)
			)
			(layer "F.Fab")
		)
		(fp_line
			(start 1.27 -3.81)
			(end -1.27 -3.81)
			(stroke
				(width 0.1)
				(type default)
			)
			(layer "F.Fab")
		)
		(fp_line
			(start 1.27 3.81)
			(end 1.27 -3.81)
			(stroke
				(width 0.1)
				(type default)
			)
			(layer "F.Fab")
		)
		(fp_poly
			(pts
				(xy 4.3942 -3.048) (xy 4.3942 -2.032) (xy 3.3782 -2.54)
			)
			(stroke
				(width 0)
				(type default)
			)
			(fill yes)
			(layer "F.Fab")
		)
		(fp_text user "3"
			(at 3.921252 2.54 90)
			(unlocked yes)
			(layer "F.SilkS")
			(effects
				(font
					(size 0.7874 0.5842)
					(thickness 0.1524)
				)
			)
		)
		(fp_text user "3"
			(at 3.921252 2.54 90)
			(unlocked yes)
			(layer "F.Fab")
			(effects
				(font
					(size 0.7874 0.5842)
					(thickness 0.1524)
				)
			)
		)
		(pad "1" smd rect
			(at 1.459992 -2.54 90)
			(size 1.27 3.429)
			(layers "F.Cu" "F.Mask" "F.Paste")
			(net "SMB_PJP1_SDA")
		)
		(pad "2" smd rect
			(at -1.459992 0 90)
			(size 1.27 3.429)
			(layers "F.Cu" "F.Mask" "F.Paste")
			(net "SMB_PJP1_SCL")
		)
		(pad "3" smd rect
			(at 1.459992 2.54 90)
			(size 1.27 3.429)
			(layers "F.Cu" "F.Mask" "F.Paste")
			(net "GND")
		)
	)
)
